# T6G (Grand Teton) — schematic netlist excerpt (pin names and nets, part order shuffled) for the footprints in the layout excerpt that follows; sources: Cadence DE-HDL packaged netlist, KiCad conversion of 04192023_DAF0TMB3IC0_F0TG_MB_C_brd_V02_OCP.brd

C659  Q_CAP  0.1UF 10V 10% X7S  pkg C0201  page 290 : A = P0V9_CPU0_RT1_2A ; B = GND
C390  Q_CAP  1UF 4V 20% X6S  pkg 0201  page 345 : A = P0V9_CPU1_RT2_2A_2D ; B = GND
C395  Q_CAP  0.1UF 10V 10% X7S  pkg C0201  page 345 : A = P0V9_CPU1_RT2_2A ; B = GND
C6093  Q_CAP  1PF 50V 0.05P COG  pkg C0402  page 179 : A = P3V3_AUX_CPU0_USB2_AVDD33 ; B = GND

(kicad_pcb
	(version 20260206)
	(generator "pcbnew")
	(generator_version "10.0")
	(general
		(thickness 1.6)
		(legacy_teardrops no)
	)
	(paper "A4")
	(title_block
		(title "04192023_DAF0TMB3IC0_F0TG_MB_C_brd_V02_OCP.brd")
		(comment 1 "Grand Teton / footprints 5058-5061 of 8354")
	)
	(layers
		(0 "F.Cu" signal "TOP")
		(4 "In1.Cu" signal "GND")
		(6 "In2.Cu" signal "IN1")
		(8 "In3.Cu" signal "GND1")
		(10 "In4.Cu" signal "IN2")
		(12 "In5.Cu" signal "GND2")
		(14 "In6.Cu" signal "IN3")
		(16 "In7.Cu" signal "GND3")
		(18 "In8.Cu" signal "VCC")
		(20 "In9.Cu" signal "VCC1")
		(22 "In10.Cu" signal "GND4")
		(24 "In11.Cu" signal "IN4")
		(26 "In12.Cu" signal "GND5")
		(28 "In13.Cu" signal "IN5")
		(30 "In14.Cu" signal "GND6")
		(32 "In15.Cu" signal "IN6")
		(34 "In16.Cu" signal "GND7")
		(2 "B.Cu" signal "BOTTOM")
		(9 "F.Adhes" user "F.Adhesive")
		(11 "B.Adhes" user "B.Adhesive")
		(13 "F.Paste" user "Package Geometry/Pastemask Top")
		(15 "B.Paste" user "Package Geometry/Pastemask Bottom")
		(5 "F.SilkS" user "Ref Des/Silkscreen Top")
		(7 "B.SilkS" user "Ref Des/Silkscreen Bottom")
		(1 "F.Mask" user "Board Geometry/Soldermask Top")
		(3 "B.Mask" user "Board Geometry/Soldermask Bottom")
		(17 "Dwgs.User" user "User.Drawings")
		(19 "Cmts.User" user "User.Comments")
		(21 "Eco1.User" user "User.Eco1")
		(23 "Eco2.User" user "User.Eco2")
		(25 "Edge.Cuts" user "Board Geometry/Outline")
		(27 "Margin" user)
		(31 "F.CrtYd" user "Package Geometry/Place Bound Top")
		(29 "B.CrtYd" user "Package Geometry/Place Bound Bottom")
		(35 "F.Fab" user "Ref Des/Assembly Top")
		(33 "B.Fab" user "Ref Des/Assembly Bottom")
	)
	(footprint ""
		(layer "B.Cu")
		(at 109.550454 -31.549086 180)
		(property "Reference" "C6093"
			(at 0 0 0)
			(layer "B.SilkS")
			(hide yes)
			(effects
				(font
					(size 1.27 1.27)
				)
				(justify mirror)
			)
		)
		(property "Value" ""
			(at 0 0 0)
			(layer "B.Fab")
			(effects
				(font
					(size 1.27 1.27)
				)
				(justify mirror)
			)
		)
		(duplicate_pad_numbers_are_jumpers no)
		(fp_line
			(start 0.7874 0.4064)
			(end 0.7874 -0.4064)
			(stroke
				(width 0.1524)
				(type default)
			)
			(layer "B.SilkS")
		)
		(fp_line
			(start 0.7874 -0.4064)
			(end -0.7874 -0.4064)
			(stroke
				(width 0.1524)
				(type default)
			)
			(layer "B.SilkS")
		)
		(fp_line
			(start -0.7874 0.4064)
			(end 0.7874 0.4064)
			(stroke
				(width 0.1524)
				(type default)
			)
			(layer "B.SilkS")
		)
		(fp_line
			(start -0.7874 -0.4064)
			(end -0.7874 0.4064)
			(stroke
				(width 0.1524)
				(type default)
			)
			(layer "B.SilkS")
		)
		(fp_line
			(start 0.67945 0.3048)
			(end 0.67945 -0.305054)
			(stroke
				(width 0.1)
				(type default)
			)
			(layer "B.Fab")
		)
		(fp_line
			(start 0.67945 -0.305054)
			(end 0.12065 -0.305054)
			(stroke
				(width 0.1)
				(type default)
			)
			(layer "B.Fab")
		)
		(fp_line
			(start 0.12065 0.3048)
			(end 0.67945 0.3048)
			(stroke
				(width 0.1)
				(type default)
			)
			(layer "B.Fab")
		)
		(fp_line
			(start 0.12065 0.2794)
			(end 0.12065 0.3048)
			(stroke
				(width 0.1)
				(type default)
			)
			(layer "B.Fab")
		)
		(fp_line
			(start 0.12065 -0.2794)
			(end -0.12065 -0.2794)
			(stroke
				(width 0.1)
				(type default)
			)
			(layer "B.Fab")
		)
		(fp_line
			(start 0.12065 -0.305054)
			(end 0.12065 -0.2794)
			(stroke
				(width 0.1)
				(type default)
			)
			(layer "B.Fab")
		)
		(fp_line
			(start -0.120396 0.3048)
			(end -0.120396 0.2794)
			(stroke
				(width 0.1)
				(type default)
			)
			(layer "B.Fab")
		)
		(fp_line
			(start -0.120396 0.2794)
			(end 0.12065 0.2794)
			(stroke
				(width 0.1)
				(type default)
			)
			(layer "B.Fab")
		)
		(fp_line
			(start -0.12065 -0.2794)
			(end -0.12065 -0.3048)
			(stroke
				(width 0.1)
				(type default)
			)
			(layer "B.Fab")
		)
		(fp_line
			(start -0.12065 -0.3048)
			(end -0.67945 -0.3048)
			(stroke
				(width 0.1)
				(type default)
			)
			(layer "B.Fab")
		)
		(fp_line
			(start -0.67945 0.3048)
			(end -0.120396 0.3048)
			(stroke
				(width 0.1)
				(type default)
			)
			(layer "B.Fab")
		)
		(fp_line
			(start -0.67945 -0.3048)
			(end -0.67945 0.3048)
			(stroke
				(width 0.1)
				(type default)
			)
			(layer "B.Fab")
		)
		(pad "1" smd circle
			(at 0.40005 0)
			(size 0 0)
			(layers "B.Cu" "B.Mask" "B.Paste")
			(net "P3V3_AUX_CPU0_USB2_AVDD33")
		)
		(pad "2" smd circle
			(at -0.40005 0)
			(size 0 0)
			(layers "B.Cu" "B.Mask" "B.Paste")
			(net "GND")
		)
	)
	(footprint ""
		(layer "B.Cu")
		(at 151.806148 -386.766562 90)
		(property "Reference" "C390"
			(at 0 0 90)
			(layer "B.SilkS")
			(hide yes)
			(effects
				(font
					(size 1.27 1.27)
				)
				(justify mirror)
			)
		)
		(property "Value" ""
			(at 0 0 90)
			(layer "B.Fab")
			(effects
				(font
					(size 1.27 1.27)
				)
				(justify mirror)
			)
		)
		(duplicate_pad_numbers_are_jumpers no)
		(fp_line
			(start 0.299974 -0.150114)
			(end -0.299974 -0.150114)
			(stroke
				(width 0.1)
				(type default)
			)
			(layer "B.Fab")
		)
		(fp_line
			(start -0.299974 -0.150114)
			(end -0.299974 0.150114)
			(stroke
				(width 0.1)
				(type default)
			)
			(layer "B.Fab")
		)
		(fp_line
			(start 0.299974 0.150114)
			(end 0.299974 -0.150114)
			(stroke
				(width 0.1)
				(type default)
			)
			(layer "B.Fab")
		)
		(fp_line
			(start -0.299974 0.150114)
			(end 0.299974 0.150114)
			(stroke
				(width 0.1)
				(type default)
			)
			(layer "B.Fab")
		)
		(pad "1" smd rect
			(at 0.2667 0 270)
			(size 0.3048 0.381)
			(layers "B.Cu" "B.Mask" "B.Paste")
			(net "P0V9_CPU1_RT2_2A_2D")
		)
		(pad "2" smd rect
			(at -0.2667 0 270)
			(size 0.3048 0.381)
			(layers "B.Cu" "B.Mask" "B.Paste")
			(net "GND")
		)
	)
	(footprint ""
		(layer "B.Cu")
		(at 165.146228 -388.011162 -90)
		(property "Reference" "C395"
			(at 0 0 90)
			(layer "B.SilkS")
			(hide yes)
			(effects
				(font
					(size 1.27 1.27)
				)
				(justify mirror)
			)
		)
		(property "Value" ""
			(at 0 0 90)
			(layer "B.Fab")
			(effects
				(font
					(size 1.27 1.27)
				)
				(justify mirror)
			)
		)
		(duplicate_pad_numbers_are_jumpers no)
		(fp_line
			(start -0.299974 0.150114)
			(end 0.299974 0.150114)
			(stroke
				(width 0.1)
				(type default)
			)
			(layer "B.Fab")
		)
		(fp_line
			(start 0.299974 0.150114)
			(end 0.299974 -0.150114)
			(stroke
				(width 0.1)
				(type default)
			)
			(layer "B.Fab")
		)
		(fp_line
			(start -0.299974 -0.150114)
			(end -0.299974 0.150114)
			(stroke
				(width 0.1)
				(type default)
			)
			(layer "B.Fab")
		)
		(fp_line
			(start 0.299974 -0.150114)
			(end -0.299974 -0.150114)
			(stroke
				(width 0.1)
				(type default)
			)
			(layer "B.Fab")
		)
		(pad "1" smd rect
			(at 0.2667 0 90)
			(size 0.3048 0.381)
			(layers "B.Cu" "B.Mask" "B.Paste")
			(net "P0V9_CPU1_RT2_2A")
		)
		(pad "2" smd rect
			(at -0.2667 0 90)
			(size 0.3048 0.381)
			(layers "B.Cu" "B.Mask" "B.Paste")
			(net "GND")
		)
	)
	(footprint ""
		(layer "B.Cu")
		(at 351.645982 -396.393162 -90)
		(property "Reference" "C659"
			(at 0 0 90)
			(layer "B.SilkS")
			(hide yes)
			(effects
				(font
					(size 1.27 1.27)
				)
				(justify mirror)
			)
		)
		(property "Value" ""
			(at 0 0 90)
			(layer "B.Fab")
			(effects
				(font
					(size 1.27 1.27)
				)
				(justify mirror)
			)
		)
		(duplicate_pad_numbers_are_jumpers no)
		(fp_line
			(start -0.299974 0.150114)
			(end 0.299974 0.150114)
			(stroke
				(width 0.1)
				(type default)
			)
			(layer "B.Fab")
		)
		(fp_line
			(start 0.299974 0.150114)
			(end 0.299974 -0.150114)
			(stroke
				(width 0.1)
				(type default)
			)
			(layer "B.Fab")
		)
		(fp_line
			(start -0.299974 -0.150114)
			(end -0.299974 0.150114)
			(stroke
				(width 0.1)
				(type default)
			)
			(layer "B.Fab")
		)
		(fp_line
			(start 0.299974 -0.150114)
			(end -0.299974 -0.150114)
			(stroke
				(width 0.1)
				(type default)
			)
			(layer "B.Fab")
		)
		(pad "1" smd rect
			(at 0.2667 0 90)
			(size 0.3048 0.381)
			(layers "B.Cu" "B.Mask" "B.Paste")
			(net "P0V9_CPU0_RT1_2A")
		)
		(pad "2" smd rect
			(at -0.2667 0 90)
			(size 0.3048 0.381)
			(layers "B.Cu" "B.Mask" "B.Paste")
			(net "GND")
		)
	)
)
